(kicad_pcb
	(version 20260206)
	(generator "pcbnew")
	(generator_version "10.0")
	(general
		(thickness 1.6)
		(legacy_teardrops no)
	)
	(paper "A4")
	(title_block
		(title "01162023_DA0F0TEBIF0_F0T_Expander_BD_F_brd_V02_OCP.brd")
		(comment 1 "Grand Teton / footprints 7101-7107 of 9728")
	)
	(layers
		(0 "F.Cu" signal "TOP")
		(4 "In1.Cu" signal "GND")
		(6 "In2.Cu" signal "VCC")
		(8 "In3.Cu" signal "VCC1")
		(10 "In4.Cu" signal "GND1")
		(12 "In5.Cu" signal "IN1")
		(14 "In6.Cu" signal "GND2")
		(16 "In7.Cu" signal "IN2")
		(18 "In8.Cu" signal "GND3")
		(20 "In9.Cu" signal "IN3")
		(22 "In10.Cu" signal "GND4")
		(24 "In11.Cu" signal "IN4")
		(26 "In12.Cu" signal "GND5")
		(28 "In13.Cu" signal "IN5")
		(30 "In14.Cu" signal "GND6")
		(32 "In15.Cu" signal "IN6")
		(34 "In16.Cu" signal "GND7")
		(2 "B.Cu" signal "BOTTOM")
		(9 "F.Adhes" user "F.Adhesive")
		(11 "B.Adhes" user "B.Adhesive")
		(13 "F.Paste" user "Package Geometry/Pastemask Top")
		(15 "B.Paste" user "Package Geometry/Pastemask Bottom")
		(5 "F.SilkS" user "Ref Des/Silkscreen Top")
		(7 "B.SilkS" user "Ref Des/Silkscreen Bottom")
		(1 "F.Mask" user "Board Geometry/Soldermask Top")
		(3 "B.Mask" user "Board Geometry/Soldermask Bottom")
		(17 "Dwgs.User" user "User.Drawings")
		(19 "Cmts.User" user "User.Comments")
		(21 "Eco1.User" user "User.Eco1")
		(23 "Eco2.User" user "User.Eco2")
		(25 "Edge.Cuts" user "Board Geometry/Outline")
		(27 "Margin" user)
		(31 "F.CrtYd" user "Package Geometry/Place Bound Top")
		(29 "B.CrtYd" user "Package Geometry/Place Bound Bottom")
		(35 "F.Fab" user "Ref Des/Assembly Top")
		(33 "B.Fab" user "Ref Des/Assembly Bottom")
	)
	(footprint ""
		(layer "F.Cu")
		(at 280.085546 -27.092148 -90)
		(property "Reference" "R5761"
			(at 0 0 270)
			(layer "F.SilkS")
			(hide yes)
			(effects
				(font
					(size 1.27 1.27)
				)
			)
		)
		(property "Value" ""
			(at 0 0 270)
			(layer "F.Fab")
			(effects
				(font
					(size 1.27 1.27)
				)
			)
		)
		(duplicate_pad_numbers_are_jumpers no)
		(fp_line
			(start -0.7874 0.4064)
			(end -0.7874 -0.4064)
			(stroke
				(width 0.1524)
				(type default)
			)
			(layer "F.SilkS")
		)
		(fp_line
			(start 0.7874 0.4064)
			(end -0.7874 0.4064)
			(stroke
				(width 0.1524)
				(type default)
			)
			(layer "F.SilkS")
		)
		(fp_line
			(start -0.7874 -0.4064)
			(end 0.7874 -0.4064)
			(stroke
				(width 0.1524)
				(type default)
			)
			(layer "F.SilkS")
		)
		(fp_line
			(start 0.7874 -0.4064)
			(end 0.7874 0.4064)
			(stroke
				(width 0.1524)
				(type default)
			)
			(layer "F.SilkS")
		)
		(fp_line
			(start -0.67945 0.3048)
			(end -0.67945 -0.305054)
			(stroke
				(width 0.1)
				(type default)
			)
			(layer "F.Fab")
		)
		(fp_line
			(start -0.12065 0.3048)
			(end -0.67945 0.3048)
			(stroke
				(width 0.1)
				(type default)
			)
			(layer "F.Fab")
		)
		(fp_line
			(start 0.120396 0.3048)
			(end 0.120396 0.2794)
			(stroke
				(width 0.1)
				(type default)
			)
			(layer "F.Fab")
		)
		(fp_line
			(start 0.67945 0.3048)
			(end 0.120396 0.3048)
			(stroke
				(width 0.1)
				(type default)
			)
			(layer "F.Fab")
		)
		(fp_line
			(start -0.12065 0.2794)
			(end -0.12065 0.3048)
			(stroke
				(width 0.1)
				(type default)
			)
			(layer "F.Fab")
		)
		(fp_line
			(start 0.120396 0.2794)
			(end -0.12065 0.2794)
			(stroke
				(width 0.1)
				(type default)
			)
			(layer "F.Fab")
		)
		(fp_line
			(start -0.12065 -0.2794)
			(end 0.12065 -0.2794)
			(stroke
				(width 0.1)
				(type default)
			)
			(layer "F.Fab")
		)
		(fp_line
			(start 0.12065 -0.2794)
			(end 0.12065 -0.3048)
			(stroke
				(width 0.1)
				(type default)
			)
			(layer "F.Fab")
		)
		(fp_line
			(start 0.12065 -0.3048)
			(end 0.67945 -0.3048)
			(stroke
				(width 0.1)
				(type default)
			)
			(layer "F.Fab")
		)
		(fp_line
			(start 0.67945 -0.3048)
			(end 0.67945 0.3048)
			(stroke
				(width 0.1)
				(type default)
			)
			(layer "F.Fab")
		)
		(fp_line
			(start -0.67945 -0.305054)
			(end -0.12065 -0.305054)
			(stroke
				(width 0.1)
				(type default)
			)
			(layer "F.Fab")
		)
		(fp_line
			(start -0.12065 -0.305054)
			(end -0.12065 -0.2794)
			(stroke
				(width 0.1)
				(type default)
			)
			(layer "F.Fab")
		)
		(pad "1" smd circle
			(at -0.40005 0 270)
			(size 0 0)
			(layers "F.Cu" "F.Mask" "F.Paste")
			(net "P3V3_SSD9")
		)
		(pad "2" smd circle
			(at 0.40005 0 270)
			(size 0 0)
			(layers "F.Cu" "F.Mask" "F.Paste")
			(net "SSD9_LED_ISO_N")
		)
	)
	(footprint ""
		(layer "F.Cu")
		(at 71.246746 -38.49116 180)
		(property "Reference" "R5889"
			(at 0 0 180)
			(layer "F.SilkS")
			(hide yes)
			(effects
				(font
					(size 1.27 1.27)
				)
			)
		)
		(property "Value" ""
			(at 0 0 180)
			(layer "F.Fab")
			(effects
				(font
					(size 1.27 1.27)
				)
			)
		)
		(duplicate_pad_numbers_are_jumpers no)
		(fp_line
			(start 0.7874 0.4064)
			(end -0.7874 0.4064)
			(stroke
				(width 0.1524)
				(type default)
			)
			(layer "F.SilkS")
		)
		(fp_line
			(start 0.7874 -0.4064)
			(end 0.7874 0.4064)
			(stroke
				(width 0.1524)
				(type default)
			)
			(layer "F.SilkS")
		)
		(fp_line
			(start -0.7874 0.4064)
			(end -0.7874 -0.4064)
			(stroke
				(width 0.1524)
				(type default)
			)
			(layer "F.SilkS")
		)
		(fp_line
			(start -0.7874 -0.4064)
			(end 0.7874 -0.4064)
			(stroke
				(width 0.1524)
				(type default)
			)
			(layer "F.SilkS")
		)
		(fp_line
			(start 0.67945 0.3048)
			(end 0.120396 0.3048)
			(stroke
				(width 0.1)
				(type default)
			)
			(layer "F.Fab")
		)
		(fp_line
			(start 0.67945 -0.3048)
			(end 0.67945 0.3048)
			(stroke
				(width 0.1)
				(type default)
			)
			(layer "F.Fab")
		)
		(fp_line
			(start 0.12065 -0.2794)
			(end 0.12065 -0.3048)
			(stroke
				(width 0.1)
				(type default)
			)
			(layer "F.Fab")
		)
		(fp_line
			(start 0.12065 -0.3048)
			(end 0.67945 -0.3048)
			(stroke
				(width 0.1)
				(type default)
			)
			(layer "F.Fab")
		)
		(fp_line
			(start 0.120396 0.3048)
			(end 0.120396 0.2794)
			(stroke
				(width 0.1)
				(type default)
			)
			(layer "F.Fab")
		)
		(fp_line
			(start 0.120396 0.2794)
			(end -0.12065 0.2794)
			(stroke
				(width 0.1)
				(type default)
			)
			(layer "F.Fab")
		)
		(fp_line
			(start -0.12065 0.3048)
			(end -0.67945 0.3048)
			(stroke
				(width 0.1)
				(type default)
			)
			(layer "F.Fab")
		)
		(fp_line
			(start -0.12065 0.2794)
			(end -0.12065 0.3048)
			(stroke
				(width 0.1)
				(type default)
			)
			(layer "F.Fab")
		)
		(fp_line
			(start -0.12065 -0.2794)
			(end 0.12065 -0.2794)
			(stroke
				(width 0.1)
				(type default)
			)
			(layer "F.Fab")
		)
		(fp_line
			(start -0.12065 -0.305054)
			(end -0.12065 -0.2794)
			(stroke
				(width 0.1)
				(type default)
			)
			(layer "F.Fab")
		)
		(fp_line
			(start -0.67945 0.3048)
			(end -0.67945 -0.305054)
			(stroke
				(width 0.1)
				(type default)
			)
			(layer "F.Fab")
		)
		(fp_line
			(start -0.67945 -0.305054)
			(end -0.12065 -0.305054)
			(stroke
				(width 0.1)
				(type default)
			)
			(layer "F.Fab")
		)
		(pad "1" smd circle
			(at -0.40005 0 180)
			(size 0 0)
			(layers "F.Cu" "F.Mask" "F.Paste")
			(net "P3V3_SSD3_PG_G1")
		)
		(pad "2" smd circle
			(at 0.40005 0 180)
			(size 0 0)
			(layers "F.Cu" "F.Mask" "F.Paste")
			(net "GND")
		)
	)
	(footprint ""
		(layer "F.Cu")
		(at 188.587634 -25.342342 -90)
		(property "Reference" "R428"
			(at 0 0 270)
			(layer "F.SilkS")
			(hide yes)
			(effects
				(font
					(size 1.27 1.27)
				)
			)
		)
		(property "Value" ""
			(at 0 0 270)
			(layer "F.Fab")
			(effects
				(font
					(size 1.27 1.27)
				)
			)
		)
		(duplicate_pad_numbers_are_jumpers no)
		(fp_line
			(start -0.7874 0.4064)
			(end -0.7874 -0.4064)
			(stroke
				(width 0.1524)
				(type default)
			)
			(layer "F.SilkS")
		)
		(fp_line
			(start 0.7874 0.4064)
			(end -0.7874 0.4064)
			(stroke
				(width 0.1524)
				(type default)
			)
			(layer "F.SilkS")
		)
		(fp_line
			(start -0.7874 -0.4064)
			(end 0.7874 -0.4064)
			(stroke
				(width 0.1524)
				(type default)
			)
			(layer "F.SilkS")
		)
		(fp_line
			(start 0.7874 -0.4064)
			(end 0.7874 0.4064)
			(stroke
				(width 0.1524)
				(type default)
			)
			(layer "F.SilkS")
		)
		(fp_line
			(start -0.67945 0.3048)
			(end -0.67945 -0.305054)
			(stroke
				(width 0.1)
				(type default)
			)
			(layer "F.Fab")
		)
		(fp_line
			(start -0.12065 0.3048)
			(end -0.67945 0.3048)
			(stroke
				(width 0.1)
				(type default)
			)
			(layer "F.Fab")
		)
		(fp_line
			(start 0.120396 0.3048)
			(end 0.120396 0.2794)
			(stroke
				(width 0.1)
				(type default)
			)
			(layer "F.Fab")
		)
		(fp_line
			(start 0.67945 0.3048)
			(end 0.120396 0.3048)
			(stroke
				(width 0.1)
				(type default)
			)
			(layer "F.Fab")
		)
		(fp_line
			(start -0.12065 0.2794)
			(end -0.12065 0.3048)
			(stroke
				(width 0.1)
				(type default)
			)
			(layer "F.Fab")
		)
		(fp_line
			(start 0.120396 0.2794)
			(end -0.12065 0.2794)
			(stroke
				(width 0.1)
				(type default)
			)
			(layer "F.Fab")
		)
		(fp_line
			(start -0.12065 -0.2794)
			(end 0.12065 -0.2794)
			(stroke
				(width 0.1)
				(type default)
			)
			(layer "F.Fab")
		)
		(fp_line
			(start 0.12065 -0.2794)
			(end 0.12065 -0.3048)
			(stroke
				(width 0.1)
				(type default)
			)
			(layer "F.Fab")
		)
		(fp_line
			(start 0.12065 -0.3048)
			(end 0.67945 -0.3048)
			(stroke
				(width 0.1)
				(type default)
			)
			(layer "F.Fab")
		)
		(fp_line
			(start 0.67945 -0.3048)
			(end 0.67945 0.3048)
			(stroke
				(width 0.1)
				(type default)
			)
			(layer "F.Fab")
		)
		(fp_line
			(start -0.67945 -0.305054)
			(end -0.12065 -0.305054)
			(stroke
				(width 0.1)
				(type default)
			)
			(layer "F.Fab")
		)
		(fp_line
			(start -0.12065 -0.305054)
			(end -0.12065 -0.2794)
			(stroke
				(width 0.1)
				(type default)
			)
			(layer "F.Fab")
		)
		(pad "1" smd circle
			(at -0.40005 0 270)
			(size 0 0)
			(layers "F.Cu" "F.Mask" "F.Paste")
			(net "GND")
		)
		(pad "2" smd circle
			(at 0.40005 0 270)
			(size 0 0)
			(layers "F.Cu" "F.Mask" "F.Paste")
			(net "DUALPORT_N_SSD6")
		)
	)
	(footprint ""
		(layer "F.Cu")
		(at 27.890216 -260.949694)
		(property "Reference" "R4567"
			(at 0 0 0)
			(layer "F.SilkS")
			(hide yes)
			(effects
				(font
					(size 1.27 1.27)
				)
			)
		)
		(property "Value" ""
			(at 0 0 0)
			(layer "F.Fab")
			(effects
				(font
					(size 1.27 1.27)
				)
			)
		)
		(duplicate_pad_numbers_are_jumpers no)
		(fp_line
			(start -0.7874 -0.4064)
			(end 0.7874 -0.4064)
			(stroke
				(width 0.1524)
				(type default)
			)
			(layer "F.SilkS")
		)
		(fp_line
			(start -0.7874 0.4064)
			(end -0.7874 -0.4064)
			(stroke
				(width 0.1524)
				(type default)
			)
			(layer "F.SilkS")
		)
		(fp_line
			(start 0.7874 -0.4064)
			(end 0.7874 0.4064)
			(stroke
				(width 0.1524)
				(type default)
			)
			(layer "F.SilkS")
		)
		(fp_line
			(start 0.7874 0.4064)
			(end -0.7874 0.4064)
			(stroke
				(width 0.1524)
				(type default)
			)
			(layer "F.SilkS")
		)
		(fp_line
			(start -0.67945 -0.305054)
			(end -0.12065 -0.305054)
			(stroke
				(width 0.1)
				(type default)
			)
			(layer "F.Fab")
		)
		(fp_line
			(start -0.67945 0.3048)
			(end -0.67945 -0.305054)
			(stroke
				(width 0.1)
				(type default)
			)
			(layer "F.Fab")
		)
		(fp_line
			(start -0.12065 -0.305054)
			(end -0.12065 -0.2794)
			(stroke
				(width 0.1)
				(type default)
			)
			(layer "F.Fab")
		)
		(fp_line
			(start -0.12065 -0.2794)
			(end 0.12065 -0.2794)
			(stroke
				(width 0.1)
				(type default)
			)
			(layer "F.Fab")
		)
		(fp_line
			(start -0.12065 0.2794)
			(end -0.12065 0.3048)
			(stroke
				(width 0.1)
				(type default)
			)
			(layer "F.Fab")
		)
		(fp_line
			(start -0.12065 0.3048)
			(end -0.67945 0.3048)
			(stroke
				(width 0.1)
				(type default)
			)
			(layer "F.Fab")
		)
		(fp_line
			(start 0.120396 0.2794)
			(end -0.12065 0.2794)
			(stroke
				(width 0.1)
				(type default)
			)
			(layer "F.Fab")
		)
		(fp_line
			(start 0.120396 0.3048)
			(end 0.120396 0.2794)
			(stroke
				(width 0.1)
				(type default)
			)
			(layer "F.Fab")
		)
		(fp_line
			(start 0.12065 -0.3048)
			(end 0.67945 -0.3048)
			(stroke
				(width 0.1)
				(type default)
			)
			(layer "F.Fab")
		)
		(fp_line
			(start 0.12065 -0.2794)
			(end 0.12065 -0.3048)
			(stroke
				(width 0.1)
				(type default)
			)
			(layer "F.Fab")
		)
		(fp_line
			(start 0.67945 -0.3048)
			(end 0.67945 0.3048)
			(stroke
				(width 0.1)
				(type default)
			)
			(layer "F.Fab")
		)
		(fp_line
			(start 0.67945 0.3048)
			(end 0.120396 0.3048)
			(stroke
				(width 0.1)
				(type default)
			)
			(layer "F.Fab")
		)
		(pad "1" smd circle
			(at -0.40005 0)
			(size 0 0)
			(layers "F.Cu" "F.Mask" "F.Paste")
			(net "P1V8_VDDA_PEX0")
		)
		(pad "2" smd circle
			(at 0.40005 0)
			(size 0 0)
			(layers "F.Cu" "F.Mask" "F.Paste")
			(net "P1V8_VDDA_PEX0_R")
		)
	)
	(footprint ""
		(layer "F.Cu")
		(at 36.638484 -123.71324)
		(property "Reference" "C44"
			(at 0 0 0)
			(layer "F.SilkS")
			(hide yes)
			(effects
				(font
					(size 1.27 1.27)
				)
			)
		)
		(property "Value" ""
			(at 0 0 0)
			(layer "F.Fab")
			(effects
				(font
					(size 1.27 1.27)
				)
			)
		)
		(duplicate_pad_numbers_are_jumpers no)
		(fp_line
			(start -0.299974 -0.150114)
			(end 0.299974 -0.150114)
			(stroke
				(width 0.1)
				(type default)
			)
			(layer "F.Fab")
		)
		(fp_line
			(start -0.299974 0.150114)
			(end -0.299974 -0.150114)
			(stroke
				(width 0.1)
				(type default)
			)
			(layer "F.Fab")
		)
		(fp_line
			(start 0.299974 -0.150114)
			(end 0.299974 0.150114)
			(stroke
				(width 0.1)
				(type default)
			)
			(layer "F.Fab")
		)
		(fp_line
			(start 0.299974 0.150114)
			(end -0.299974 0.150114)
			(stroke
				(width 0.1)
				(type default)
			)
			(layer "F.Fab")
		)
		(pad "1" smd rect
			(at -0.2667 0)
			(size 0.3048 0.381)
			(layers "F.Cu" "F.Mask" "F.Paste")
			(net "P5E_PEX0_STN1_TX_DN<26>")
		)
		(pad "2" smd rect
			(at 0.2667 0)
			(size 0.3048 0.381)
			(layers "F.Cu" "F.Mask" "F.Paste")
			(net "P5E_PEX0_STN1_TX_C_DN<26>")
		)
	)
	(footprint ""
		(layer "F.Cu")
		(at 270.980662 -350.098614 90)
		(property "Reference" "C2343"
			(at 0 0 90)
			(layer "F.SilkS")
			(hide yes)
			(effects
				(font
					(size 1.27 1.27)
				)
			)
		)
		(property "Value" ""
			(at 0 0 90)
			(layer "F.Fab")
			(effects
				(font
					(size 1.27 1.27)
				)
			)
		)
		(duplicate_pad_numbers_are_jumpers no)
		(fp_line
			(start 0.299974 -0.150114)
			(end 0.299974 0.150114)
			(stroke
				(width 0.1)
				(type default)
			)
			(layer "F.Fab")
		)
		(fp_line
			(start -0.299974 -0.150114)
			(end 0.299974 -0.150114)
			(stroke
				(width 0.1)
				(type default)
			)
			(layer "F.Fab")
		)
		(fp_line
			(start 0.299974 0.150114)
			(end -0.299974 0.150114)
			(stroke
				(width 0.1)
				(type default)
			)
			(layer "F.Fab")
		)
		(fp_line
			(start -0.299974 0.150114)
			(end -0.299974 -0.150114)
			(stroke
				(width 0.1)
				(type default)
			)
			(layer "F.Fab")
		)
		(pad "1" smd rect
			(at -0.2667 0 90)
			(size 0.3048 0.381)
			(layers "F.Cu" "F.Mask" "F.Paste")
			(net "P5E_PEX2_STN4_TX_DP<78>")
		)
		(pad "2" smd rect
			(at 0.2667 0 90)
			(size 0.3048 0.381)
			(layers "F.Cu" "F.Mask" "F.Paste")
			(net "P5E_PEX2_STN4_TX_C_DP<78>")
		)
	)
	(footprint ""
		(layer "F.Cu")
		(at 376.809 -174.15002 180)
		(property "Reference" "R4679"
			(at 0 0 180)
			(layer "F.SilkS")
			(hide yes)
			(effects
				(font
					(size 1.27 1.27)
				)
			)
		)
		(property "Value" ""
			(at 0 0 180)
			(layer "F.Fab")
			(effects
				(font
					(size 1.27 1.27)
				)
			)
		)
		(duplicate_pad_numbers_are_jumpers no)
		(fp_line
			(start 0.7874 0.4064)
			(end -0.7874 0.4064)
			(stroke
				(width 0.1524)
				(type default)
			)
			(layer "F.SilkS")
		)
		(fp_line
			(start 0.7874 -0.4064)
			(end 0.7874 0.4064)
			(stroke
				(width 0.1524)
				(type default)
			)
			(layer "F.SilkS")
		)
		(fp_line
			(start -0.7874 0.4064)
			(end -0.7874 -0.4064)
			(stroke
				(width 0.1524)
				(type default)
			)
			(layer "F.SilkS")
		)
		(fp_line
			(start -0.7874 -0.4064)
			(end 0.7874 -0.4064)
			(stroke
				(width 0.1524)
				(type default)
			)
			(layer "F.SilkS")
		)
		(fp_line
			(start 0.67945 0.3048)
			(end 0.120396 0.3048)
			(stroke
				(width 0.1)
				(type default)
			)
			(layer "F.Fab")
		)
		(fp_line
			(start 0.67945 -0.3048)
			(end 0.67945 0.3048)
			(stroke
				(width 0.1)
				(type default)
			)
			(layer "F.Fab")
		)
		(fp_line
			(start 0.12065 -0.2794)
			(end 0.12065 -0.3048)
			(stroke
				(width 0.1)
				(type default)
			)
			(layer "F.Fab")
		)
		(fp_line
			(start 0.12065 -0.3048)
			(end 0.67945 -0.3048)
			(stroke
				(width 0.1)
				(type default)
			)
			(layer "F.Fab")
		)
		(fp_line
			(start 0.120396 0.3048)
			(end 0.120396 0.2794)
			(stroke
				(width 0.1)
				(type default)
			)
			(layer "F.Fab")
		)
		(fp_line
			(start 0.120396 0.2794)
			(end -0.12065 0.2794)
			(stroke
				(width 0.1)
				(type default)
			)
			(layer "F.Fab")
		)
		(fp_line
			(start -0.12065 0.3048)
			(end -0.67945 0.3048)
			(stroke
				(width 0.1)
				(type default)
			)
			(layer "F.Fab")
		)
		(fp_line
			(start -0.12065 0.2794)
			(end -0.12065 0.3048)
			(stroke
				(width 0.1)
				(type default)
			)
			(layer "F.Fab")
		)
		(fp_line
			(start -0.12065 -0.2794)
			(end 0.12065 -0.2794)
			(stroke
				(width 0.1)
				(type default)
			)
			(layer "F.Fab")
		)
		(fp_line
			(start -0.12065 -0.305054)
			(end -0.12065 -0.2794)
			(stroke
				(width 0.1)
				(type default)
			)
			(layer "F.Fab")
		)
		(fp_line
			(start -0.67945 0.3048)
			(end -0.67945 -0.305054)
			(stroke
				(width 0.1)
				(type default)
			)
			(layer "F.Fab")
		)
		(fp_line
			(start -0.67945 -0.305054)
			(end -0.12065 -0.305054)
			(stroke
				(width 0.1)
				(type default)
			)
			(layer "F.Fab")
		)
		(pad "1" smd circle
			(at -0.40005 0 180)
			(size 0 0)
			(layers "F.Cu" "F.Mask" "F.Paste")
			(net "NIC3_PEX_PWR_EN_R")
		)
		(pad "2" smd circle
			(at 0.40005 0 180)
			(size 0 0)
			(layers "F.Cu" "F.Mask" "F.Paste")
			(net "GND")
		)
	)
)
